#ISCELL
  pure_quanta quanta_title_block_c *
  *
#ISCELL
  standard offpage *
  page169_i1
#ISCELL
  standard tap *
  page169_i10
#ISCELL
  standard tap *
  page169_i100
#ISCELL
  standard tap *
  page169_i101
#ISCELL
  standard tap *
  page169_i102
#ISCELL
  standard tap *
  page169_i103
#ISCELL
  standard tap *
  page169_i104
#ISCELL
  standard tap *
  page169_i105
#ISCELL
  standard tap *
  page169_i106
#ISCELL
  standard tap *
  page169_i107
#ISCELL
  standard tap *
  page169_i108
#ISCELL
  standard tap *
  page169_i109
#ISCELL
  standard tap *
  page169_i11
#ISCELL
  standard tap *
  page169_i110
#ISCELL
  standard tap *
  page169_i111
#ISCELL
  standard tap *
  page169_i112
#CELL
  pure_quanta q_cap_diffbus *
  page169_i113
#CELL
  pure_quanta q_cap_diffbus *
  page169_i114
#CELL
  pure_quanta q_cap_diffbus *
  page169_i115
#CELL
  pure_quanta q_cap_diffbus *
  page169_i116
#CELL
  pure_quanta q_cap_diffbus *
  page169_i117
#CELL
  pure_quanta q_cap_diffbus *
  page169_i118
#CELL
  pure_quanta q_cap_diffbus *
  page169_i119
#ISCELL
  standard tap *
  page169_i12
#CELL
  pure_quanta q_cap_diffbus *
  page169_i120
#CELL
  pure_quanta q_cap_diffbus *
  page169_i121
#CELL
  pure_quanta q_cap_diffbus *
  page169_i122
#CELL
  pure_quanta q_cap_diffbus *
  page169_i123
#CELL
  pure_quanta q_cap_diffbus *
  page169_i124
#CELL
  pure_quanta q_cap_diffbus *
  page169_i125
#CELL
  pure_quanta q_cap_diffbus *
  page169_i126
#CELL
  pure_quanta q_cap_diffbus *
  page169_i127
#CELL
  pure_quanta q_cap_diffbus *
  page169_i128
#ISCELL
  standard tap *
  page169_i129
#ISCELL
  standard tap *
  page169_i13
#ISCELL
  standard tap *
  page169_i130
#ISCELL
  standard tap *
  page169_i131
#ISCELL
  standard tap *
  page169_i132
#ISCELL
  standard tap *
  page169_i133
#ISCELL
  standard tap *
  page169_i134
#ISCELL
  standard tap *
  page169_i135
#ISCELL
  standard tap *
  page169_i136
#ISCELL
  standard tap *
  page169_i137
#ISCELL
  standard tap *
  page169_i138
#ISCELL
  standard tap *
  page169_i139
#ISCELL
  standard tap *
  page169_i14
#ISCELL
  standard tap *
  page169_i140
#ISCELL
  standard tap *
  page169_i141
#ISCELL
  standard tap *
  page169_i142
#ISCELL
  standard tap *
  page169_i143
#ISCELL
  standard tap *
  page169_i144
#ISCELL
  standard offpage *
  page169_i145
#ISCELL
  standard offpage *
  page169_i146
#ISCELL
  standard tap *
  page169_i15
#ISCELL
  standard tap *
  page169_i16
#ISCELL
  standard tap *
  page169_i17
#ISCELL
  standard tap *
  page169_i18
#ISCELL
  standard tap *
  page169_i19
#ISCELL
  standard offpage *
  page169_i2
#ISCELL
  standard tap *
  page169_i20
#CELL
  pure_quanta q_cap_diffbus *
  page169_i21
#CELL
  pure_quanta q_cap_diffbus *
  page169_i22
#CELL
  pure_quanta q_cap_diffbus *
  page169_i23
#CELL
  pure_quanta q_cap_diffbus *
  page169_i24
#CELL
  pure_quanta q_cap_diffbus *
  page169_i25
#CELL
  pure_quanta q_cap_diffbus *
  page169_i26
#CELL
  pure_quanta q_cap_diffbus *
  page169_i27
#CELL
  pure_quanta q_cap_diffbus *
  page169_i28
#CELL
  pure_quanta q_cap_diffbus *
  page169_i29
#CELL
  pure_quanta q_cap_diffbus *
  page169_i30
#CELL
  pure_quanta q_cap_diffbus *
  page169_i31
#CELL
  pure_quanta q_cap_diffbus *
  page169_i32
#CELL
  pure_quanta q_cap_diffbus *
  page169_i33
#CELL
  pure_quanta q_cap_diffbus *
  page169_i34
#CELL
  pure_quanta q_cap_diffbus *
  page169_i35
#CELL
  pure_quanta q_cap_diffbus *
  page169_i36
#ISCELL
  standard tap *
  page169_i5
#ISCELL
  standard tap *
  page169_i6
#ISCELL
  standard tap *
  page169_i7
#ISCELL
  standard tap *
  page169_i76
#ISCELL
  standard tap *
  page169_i77
#ISCELL
  standard tap *
  page169_i78
#ISCELL
  standard tap *
  page169_i79
#ISCELL
  standard tap *
  page169_i8
#ISCELL
  standard tap *
  page169_i80
#ISCELL
  standard tap *
  page169_i81
#ISCELL
  standard tap *
  page169_i82
#ISCELL
  standard tap *
  page169_i83
#ISCELL
  standard tap *
  page169_i85
#ISCELL
  standard tap *
  page169_i86
#ISCELL
  standard tap *
  page169_i87
#ISCELL
  standard tap *
  page169_i88
#ISCELL
  standard tap *
  page169_i89
#ISCELL
  standard tap *
  page169_i9
#ISCELL
  standard tap *
  page169_i90
#ISCELL
  standard tap *
  page169_i91
#ISCELL
  standard tap *
  page169_i92
#ISCELL
  standard offpage *
  page169_i93
#ISCELL
  standard offpage *
  page169_i94
#ISCELL
  standard tap *
  page169_i95
#ISCELL
  standard tap *
  page169_i96
#ISCELL
  standard offpage *
  page169_i97
#ISCELL
  standard offpage *
  page169_i98
#ISCELL
  standard tap *
  page169_i99
